(kicad_pcb
	(version 20260206)
	(generator "pcbnew")
	(generator_version "10.0")
	(general
		(thickness 1.6)
		(legacy_teardrops no)
	)
	(paper "A4")
	(title_block
		(title "9052_F0T_PDB_Converter_Brick_F_V03_1208_1600_OCP.brd")
		(comment 1 "Grand Teton / footprints 340-344 of 578")
	)
	(layers
		(0 "F.Cu" signal "TOP")
		(4 "In1.Cu" signal "GND")
		(6 "In2.Cu" signal "IN1")
		(8 "In3.Cu" signal "GND1")
		(10 "In4.Cu" signal "VCC")
		(12 "In5.Cu" signal "VCC1")
		(14 "In6.Cu" signal "GND2")
		(16 "In7.Cu" signal "IN2")
		(18 "In8.Cu" signal "GND3")
		(2 "B.Cu" signal "BOTTOM")
		(9 "F.Adhes" user "F.Adhesive")
		(11 "B.Adhes" user "B.Adhesive")
		(13 "F.Paste" user "Package Geometry/Pastemask Top")
		(15 "B.Paste" user "Package Geometry/Pastemask Bottom")
		(5 "F.SilkS" user "Ref Des/Silkscreen Top")
		(7 "B.SilkS" user "Ref Des/Silkscreen Bottom")
		(1 "F.Mask" user "Board Geometry/Soldermask Top")
		(3 "B.Mask" user "Board Geometry/Soldermask Bottom")
		(17 "Dwgs.User" user "User.Drawings")
		(19 "Cmts.User" user "User.Comments")
		(21 "Eco1.User" user "User.Eco1")
		(23 "Eco2.User" user "User.Eco2")
		(25 "Edge.Cuts" user "Board Geometry/Outline")
		(27 "Margin" user)
		(31 "F.CrtYd" user "Package Geometry/Place Bound Top")
		(29 "B.CrtYd" user "Package Geometry/Place Bound Bottom")
		(35 "F.Fab" user "Ref Des/Assembly Top")
		(33 "B.Fab" user "Ref Des/Assembly Bottom")
	)
	(footprint ""
		(layer "B.Cu")
		(at 275.931122 -92.441522 -90)
		(property "Reference" "PD14"
			(at -0.649478 2.399792 270)
			(unlocked yes)
			(layer "B.SilkS")
			(effects
				(font
					(size 0.7874 0.5842)
					(thickness 0.1524)
				)
				(justify left mirror)
			)
		)
		(property "Value" ""
			(at 0 0 90)
			(layer "B.Fab")
			(effects
				(font
					(size 1.27 1.27)
				)
				(justify mirror)
			)
		)
		(duplicate_pad_numbers_are_jumpers no)
		(fp_line
			(start -2.032 0.7112)
			(end 1.651 0.7112)
			(stroke
				(width 0.1524)
				(type default)
			)
			(layer "B.SilkS")
		)
		(fp_line
			(start 1.651 0.7112)
			(end 1.651 -0.7112)
			(stroke
				(width 0.1524)
				(type default)
			)
			(layer "B.SilkS")
		)
		(fp_line
			(start -1.778 0.6858)
			(end -1.778 -0.6858)
			(stroke
				(width 0.1524)
				(type default)
			)
			(layer "B.SilkS")
		)
		(fp_line
			(start 0.299974 0.500126)
			(end -0.199898 0)
			(stroke
				(width 0.1524)
				(type default)
			)
			(layer "B.SilkS")
		)
		(fp_line
			(start -0.199898 0)
			(end 0.299974 -0.500126)
			(stroke
				(width 0.1524)
				(type default)
			)
			(layer "B.SilkS")
		)
		(fp_line
			(start -0.299974 -0.500126)
			(end -0.299974 0.500126)
			(stroke
				(width 0.1524)
				(type default)
			)
			(layer "B.SilkS")
		)
		(fp_line
			(start 0.299974 -0.500126)
			(end 0.299974 0.500126)
			(stroke
				(width 0.1524)
				(type default)
			)
			(layer "B.SilkS")
		)
		(fp_line
			(start -1.905 -0.6858)
			(end -1.905 0.6858)
			(stroke
				(width 0.1524)
				(type default)
			)
			(layer "B.SilkS")
		)
		(fp_line
			(start -1.651 -0.6858)
			(end -1.651 0.6858)
			(stroke
				(width 0.1524)
				(type default)
			)
			(layer "B.SilkS")
		)
		(fp_line
			(start -2.032 -0.7112)
			(end -2.032 0.7112)
			(stroke
				(width 0.1524)
				(type default)
			)
			(layer "B.SilkS")
		)
		(fp_line
			(start 1.651 -0.7112)
			(end -2.032 -0.7112)
			(stroke
				(width 0.1524)
				(type default)
			)
			(layer "B.SilkS")
		)
		(fp_line
			(start -0.899922 0.700024)
			(end 0.899922 0.700024)
			(stroke
				(width 0.1)
				(type default)
			)
			(layer "B.Fab")
		)
		(fp_line
			(start 0.899922 0.700024)
			(end 0.899922 0.175006)
			(stroke
				(width 0.1)
				(type default)
			)
			(layer "B.Fab")
		)
		(fp_line
			(start 0.299974 0.500126)
			(end -0.199898 0)
			(stroke
				(width 0.1)
				(type default)
			)
			(layer "B.Fab")
		)
		(fp_line
			(start -1.35001 0.175006)
			(end -0.899922 0.175006)
			(stroke
				(width 0.1)
				(type default)
			)
			(layer "B.Fab")
		)
		(fp_line
			(start -0.899922 0.175006)
			(end -0.899922 0.700024)
			(stroke
				(width 0.1)
				(type default)
			)
			(layer "B.Fab")
		)
		(fp_line
			(start 0.899922 0.175006)
			(end 1.35001 0.175006)
			(stroke
				(width 0.1)
				(type default)
			)
			(layer "B.Fab")
		)
		(fp_line
			(start 1.35001 0.175006)
			(end 1.35001 -0.225044)
			(stroke
				(width 0.1)
				(type default)
			)
			(layer "B.Fab")
		)
		(fp_line
			(start -0.199898 0)
			(end 0.299974 -0.500126)
			(stroke
				(width 0.1)
				(type default)
			)
			(layer "B.Fab")
		)
		(fp_line
			(start -1.35001 -0.225044)
			(end -1.35001 0.175006)
			(stroke
				(width 0.1)
				(type default)
			)
			(layer "B.Fab")
		)
		(fp_line
			(start -0.899922 -0.225044)
			(end -1.35001 -0.225044)
			(stroke
				(width 0.1)
				(type default)
			)
			(layer "B.Fab")
		)
		(fp_line
			(start 0.899922 -0.225044)
			(end 0.899922 -0.700024)
			(stroke
				(width 0.1)
				(type default)
			)
			(layer "B.Fab")
		)
		(fp_line
			(start 1.35001 -0.225044)
			(end 0.899922 -0.225044)
			(stroke
				(width 0.1)
				(type default)
			)
			(layer "B.Fab")
		)
		(fp_line
			(start -0.299974 -0.500126)
			(end -0.299974 0.500126)
			(stroke
				(width 0.1)
				(type default)
			)
			(layer "B.Fab")
		)
		(fp_line
			(start 0.299974 -0.500126)
			(end 0.299974 0.500126)
			(stroke
				(width 0.1)
				(type default)
			)
			(layer "B.Fab")
		)
		(fp_line
			(start -0.899922 -0.700024)
			(end -0.899922 -0.225044)
			(stroke
				(width 0.1)
				(type default)
			)
			(layer "B.Fab")
		)
		(fp_line
			(start 0.899922 -0.700024)
			(end -0.899922 -0.700024)
			(stroke
				(width 0.1)
				(type default)
			)
			(layer "B.Fab")
		)
		(fp_text user "-"
			(at -1.8288 -0.24765 270)
			(unlocked yes)
			(layer "B.SilkS")
			(effects
				(font
					(size 1.905 1.4224)
					(thickness 0.1524)
				)
				(justify left mirror)
			)
		)
		(fp_text user "+"
			(at 2.271522 -1.532128 270)
			(unlocked yes)
			(layer "B.SilkS")
			(effects
				(font
					(size 1.905 1.4224)
					(thickness 0.1524)
				)
				(justify left mirror)
			)
		)
		(fp_text user "+"
			(at 2.794 -0.19685 270)
			(unlocked yes)
			(layer "B.Fab")
			(effects
				(font
					(size 1.905 1.4224)
					(thickness 0.1524)
				)
				(justify left mirror)
			)
		)
		(fp_text user "-"
			(at -1.8288 -0.24765 270)
			(unlocked yes)
			(layer "B.Fab")
			(effects
				(font
					(size 1.905 1.4224)
					(thickness 0.1524)
				)
				(justify left mirror)
			)
		)
		(pad "1" smd rect
			(at 1.0922 0 270)
			(size 0.8128 0.8636)
			(layers "B.Cu" "B.Mask" "B.Paste")
			(net "P52V_HS1_4287_GATE2_R")
		)
		(pad "2" smd rect
			(at -1.0922 0 90)
			(size 0.8128 0.8636)
			(layers "B.Cu" "B.Mask" "B.Paste")
			(net "P52V_HS1_GATE2_R1")
		)
	)
	(footprint ""
		(layer "B.Cu")
		(at 282.956 -36.449 90)
		(property "Reference" "R153"
			(at 0 0 90)
			(layer "B.SilkS")
			(hide yes)
			(effects
				(font
					(size 1.27 1.27)
				)
				(justify mirror)
			)
		)
		(property "Value" ""
			(at 0 0 90)
			(layer "B.Fab")
			(effects
				(font
					(size 1.27 1.27)
				)
				(justify mirror)
			)
		)
		(duplicate_pad_numbers_are_jumpers no)
		(fp_line
			(start 0.7874 -0.4064)
			(end -0.7874 -0.4064)
			(stroke
				(width 0.1524)
				(type default)
			)
			(layer "B.SilkS")
		)
		(fp_line
			(start -0.7874 -0.4064)
			(end -0.7874 0.4064)
			(stroke
				(width 0.1524)
				(type default)
			)
			(layer "B.SilkS")
		)
		(fp_line
			(start 0.7874 0.4064)
			(end 0.7874 -0.4064)
			(stroke
				(width 0.1524)
				(type default)
			)
			(layer "B.SilkS")
		)
		(fp_line
			(start -0.7874 0.4064)
			(end 0.7874 0.4064)
			(stroke
				(width 0.1524)
				(type default)
			)
			(layer "B.SilkS")
		)
		(fp_line
			(start 0.67945 -0.305054)
			(end 0.12065 -0.305054)
			(stroke
				(width 0.1)
				(type default)
			)
			(layer "B.Fab")
		)
		(fp_line
			(start 0.12065 -0.305054)
			(end 0.12065 -0.2794)
			(stroke
				(width 0.1)
				(type default)
			)
			(layer "B.Fab")
		)
		(fp_line
			(start -0.12065 -0.3048)
			(end -0.67945 -0.3048)
			(stroke
				(width 0.1)
				(type default)
			)
			(layer "B.Fab")
		)
		(fp_line
			(start -0.67945 -0.3048)
			(end -0.67945 0.3048)
			(stroke
				(width 0.1)
				(type default)
			)
			(layer "B.Fab")
		)
		(fp_line
			(start 0.12065 -0.2794)
			(end -0.12065 -0.2794)
			(stroke
				(width 0.1)
				(type default)
			)
			(layer "B.Fab")
		)
		(fp_line
			(start -0.12065 -0.2794)
			(end -0.12065 -0.3048)
			(stroke
				(width 0.1)
				(type default)
			)
			(layer "B.Fab")
		)
		(fp_line
			(start 0.12065 0.2794)
			(end 0.12065 0.3048)
			(stroke
				(width 0.1)
				(type default)
			)
			(layer "B.Fab")
		)
		(fp_line
			(start -0.120396 0.2794)
			(end 0.12065 0.2794)
			(stroke
				(width 0.1)
				(type default)
			)
			(layer "B.Fab")
		)
		(fp_line
			(start 0.67945 0.3048)
			(end 0.67945 -0.305054)
			(stroke
				(width 0.1)
				(type default)
			)
			(layer "B.Fab")
		)
		(fp_line
			(start 0.12065 0.3048)
			(end 0.67945 0.3048)
			(stroke
				(width 0.1)
				(type default)
			)
			(layer "B.Fab")
		)
		(fp_line
			(start -0.120396 0.3048)
			(end -0.120396 0.2794)
			(stroke
				(width 0.1)
				(type default)
			)
			(layer "B.Fab")
		)
		(fp_line
			(start -0.67945 0.3048)
			(end -0.120396 0.3048)
			(stroke
				(width 0.1)
				(type default)
			)
			(layer "B.Fab")
		)
		(pad "1" smd circle
			(at 0.40005 0 270)
			(size 0 0)
			(layers "B.Cu" "B.Mask" "B.Paste")
			(net "P52V_HS1_GPO1")
		)
		(pad "2" smd circle
			(at -0.40005 0 270)
			(size 0 0)
			(layers "B.Cu" "B.Mask" "B.Paste")
			(net "P52V_HS1_FLT")
		)
	)
	(footprint ""
		(layer "B.Cu")
		(at 176.779174 -77.597 180)
		(property "Reference" "C72"
			(at 0 0 0)
			(layer "B.SilkS")
			(hide yes)
			(effects
				(font
					(size 1.27 1.27)
				)
				(justify mirror)
			)
		)
		(property "Value" ""
			(at 0 0 0)
			(layer "B.Fab")
			(effects
				(font
					(size 1.27 1.27)
				)
				(justify mirror)
			)
		)
		(duplicate_pad_numbers_are_jumpers no)
		(fp_line
			(start 0.7874 0.4064)
			(end 0.7874 -0.4064)
			(stroke
				(width 0.1524)
				(type default)
			)
			(layer "B.SilkS")
		)
		(fp_line
			(start 0.7874 -0.4064)
			(end -0.7874 -0.4064)
			(stroke
				(width 0.1524)
				(type default)
			)
			(layer "B.SilkS")
		)
		(fp_line
			(start -0.7874 0.4064)
			(end 0.7874 0.4064)
			(stroke
				(width 0.1524)
				(type default)
			)
			(layer "B.SilkS")
		)
		(fp_line
			(start -0.7874 -0.4064)
			(end -0.7874 0.4064)
			(stroke
				(width 0.1524)
				(type default)
			)
			(layer "B.SilkS")
		)
		(fp_line
			(start 0.67945 0.3048)
			(end 0.67945 -0.305054)
			(stroke
				(width 0.1)
				(type default)
			)
			(layer "B.Fab")
		)
		(fp_line
			(start 0.67945 -0.305054)
			(end 0.12065 -0.305054)
			(stroke
				(width 0.1)
				(type default)
			)
			(layer "B.Fab")
		)
		(fp_line
			(start 0.12065 0.3048)
			(end 0.67945 0.3048)
			(stroke
				(width 0.1)
				(type default)
			)
			(layer "B.Fab")
		)
		(fp_line
			(start 0.12065 0.2794)
			(end 0.12065 0.3048)
			(stroke
				(width 0.1)
				(type default)
			)
			(layer "B.Fab")
		)
		(fp_line
			(start 0.12065 -0.2794)
			(end -0.12065 -0.2794)
			(stroke
				(width 0.1)
				(type default)
			)
			(layer "B.Fab")
		)
		(fp_line
			(start 0.12065 -0.305054)
			(end 0.12065 -0.2794)
			(stroke
				(width 0.1)
				(type default)
			)
			(layer "B.Fab")
		)
		(fp_line
			(start -0.120396 0.3048)
			(end -0.120396 0.2794)
			(stroke
				(width 0.1)
				(type default)
			)
			(layer "B.Fab")
		)
		(fp_line
			(start -0.120396 0.2794)
			(end 0.12065 0.2794)
			(stroke
				(width 0.1)
				(type default)
			)
			(layer "B.Fab")
		)
		(fp_line
			(start -0.12065 -0.2794)
			(end -0.12065 -0.3048)
			(stroke
				(width 0.1)
				(type default)
			)
			(layer "B.Fab")
		)
		(fp_line
			(start -0.12065 -0.3048)
			(end -0.67945 -0.3048)
			(stroke
				(width 0.1)
				(type default)
			)
			(layer "B.Fab")
		)
		(fp_line
			(start -0.67945 0.3048)
			(end -0.120396 0.3048)
			(stroke
				(width 0.1)
				(type default)
			)
			(layer "B.Fab")
		)
		(fp_line
			(start -0.67945 -0.3048)
			(end -0.67945 0.3048)
			(stroke
				(width 0.1)
				(type default)
			)
			(layer "B.Fab")
		)
		(pad "1" smd circle
			(at 0.40005 0)
			(size 0 0)
			(layers "B.Cu" "B.Mask" "B.Paste")
			(net "P12V_BRICK2_ALERT_N")
		)
		(pad "2" smd circle
			(at -0.40005 0)
			(size 0 0)
			(layers "B.Cu" "B.Mask" "B.Paste")
			(net "GND")
		)
	)
	(footprint ""
		(layer "B.Cu")
		(at 189.611 -85.979)
		(property "Reference" "R184"
			(at 0 0 0)
			(layer "B.SilkS")
			(hide yes)
			(effects
				(font
					(size 1.27 1.27)
				)
				(justify mirror)
			)
		)
		(property "Value" ""
			(at 0 0 0)
			(layer "B.Fab")
			(effects
				(font
					(size 1.27 1.27)
				)
				(justify mirror)
			)
		)
		(duplicate_pad_numbers_are_jumpers no)
		(fp_line
			(start -0.7874 -0.4064)
			(end -0.7874 0.4064)
			(stroke
				(width 0.1524)
				(type default)
			)
			(layer "B.SilkS")
		)
		(fp_line
			(start -0.7874 0.4064)
			(end 0.7874 0.4064)
			(stroke
				(width 0.1524)
				(type default)
			)
			(layer "B.SilkS")
		)
		(fp_line
			(start 0.7874 -0.4064)
			(end -0.7874 -0.4064)
			(stroke
				(width 0.1524)
				(type default)
			)
			(layer "B.SilkS")
		)
		(fp_line
			(start 0.7874 0.4064)
			(end 0.7874 -0.4064)
			(stroke
				(width 0.1524)
				(type default)
			)
			(layer "B.SilkS")
		)
		(fp_line
			(start -0.67945 -0.3048)
			(end -0.67945 0.3048)
			(stroke
				(width 0.1)
				(type default)
			)
			(layer "B.Fab")
		)
		(fp_line
			(start -0.67945 0.3048)
			(end -0.120396 0.3048)
			(stroke
				(width 0.1)
				(type default)
			)
			(layer "B.Fab")
		)
		(fp_line
			(start -0.12065 -0.3048)
			(end -0.67945 -0.3048)
			(stroke
				(width 0.1)
				(type default)
			)
			(layer "B.Fab")
		)
		(fp_line
			(start -0.12065 -0.2794)
			(end -0.12065 -0.3048)
			(stroke
				(width 0.1)
				(type default)
			)
			(layer "B.Fab")
		)
		(fp_line
			(start -0.120396 0.2794)
			(end 0.12065 0.2794)
			(stroke
				(width 0.1)
				(type default)
			)
			(layer "B.Fab")
		)
		(fp_line
			(start -0.120396 0.3048)
			(end -0.120396 0.2794)
			(stroke
				(width 0.1)
				(type default)
			)
			(layer "B.Fab")
		)
		(fp_line
			(start 0.12065 -0.305054)
			(end 0.12065 -0.2794)
			(stroke
				(width 0.1)
				(type default)
			)
			(layer "B.Fab")
		)
		(fp_line
			(start 0.12065 -0.2794)
			(end -0.12065 -0.2794)
			(stroke
				(width 0.1)
				(type default)
			)
			(layer "B.Fab")
		)
		(fp_line
			(start 0.12065 0.2794)
			(end 0.12065 0.3048)
			(stroke
				(width 0.1)
				(type default)
			)
			(layer "B.Fab")
		)
		(fp_line
			(start 0.12065 0.3048)
			(end 0.67945 0.3048)
			(stroke
				(width 0.1)
				(type default)
			)
			(layer "B.Fab")
		)
		(fp_line
			(start 0.67945 -0.305054)
			(end 0.12065 -0.305054)
			(stroke
				(width 0.1)
				(type default)
			)
			(layer "B.Fab")
		)
		(fp_line
			(start 0.67945 0.3048)
			(end 0.67945 -0.305054)
			(stroke
				(width 0.1)
				(type default)
			)
			(layer "B.Fab")
		)
		(pad "1" smd circle
			(at 0.40005 0 180)
			(size 0 0)
			(layers "B.Cu" "B.Mask" "B.Paste")
			(net "SMB_P52V_VPDB_SCL_R")
		)
		(pad "2" smd circle
			(at -0.40005 0 180)
			(size 0 0)
			(layers "B.Cu" "B.Mask" "B.Paste")
			(net "SMB_P52V_VPDB_SCL")
		)
	)
	(footprint ""
		(layer "B.Cu")
		(at 238.76 -75.819 90)
		(property "Reference" "R75"
			(at 0 0 90)
			(layer "B.SilkS")
			(hide yes)
			(effects
				(font
					(size 1.27 1.27)
				)
				(justify mirror)
			)
		)
		(property "Value" ""
			(at 0 0 90)
			(layer "B.Fab")
			(effects
				(font
					(size 1.27 1.27)
				)
				(justify mirror)
			)
		)
		(duplicate_pad_numbers_are_jumpers no)
		(fp_line
			(start 0.7874 -0.4064)
			(end -0.7874 -0.4064)
			(stroke
				(width 0.1524)
				(type default)
			)
			(layer "B.SilkS")
		)
		(fp_line
			(start -0.7874 -0.4064)
			(end -0.7874 0.4064)
			(stroke
				(width 0.1524)
				(type default)
			)
			(layer "B.SilkS")
		)
		(fp_line
			(start 0.7874 0.4064)
			(end 0.7874 -0.4064)
			(stroke
				(width 0.1524)
				(type default)
			)
			(layer "B.SilkS")
		)
		(fp_line
			(start -0.7874 0.4064)
			(end 0.7874 0.4064)
			(stroke
				(width 0.1524)
				(type default)
			)
			(layer "B.SilkS")
		)
		(fp_line
			(start 0.67945 -0.305054)
			(end 0.12065 -0.305054)
			(stroke
				(width 0.1)
				(type default)
			)
			(layer "B.Fab")
		)
		(fp_line
			(start 0.12065 -0.305054)
			(end 0.12065 -0.2794)
			(stroke
				(width 0.1)
				(type default)
			)
			(layer "B.Fab")
		)
		(fp_line
			(start -0.12065 -0.3048)
			(end -0.67945 -0.3048)
			(stroke
				(width 0.1)
				(type default)
			)
			(layer "B.Fab")
		)
		(fp_line
			(start -0.67945 -0.3048)
			(end -0.67945 0.3048)
			(stroke
				(width 0.1)
				(type default)
			)
			(layer "B.Fab")
		)
		(fp_line
			(start 0.12065 -0.2794)
			(end -0.12065 -0.2794)
			(stroke
				(width 0.1)
				(type default)
			)
			(layer "B.Fab")
		)
		(fp_line
			(start -0.12065 -0.2794)
			(end -0.12065 -0.3048)
			(stroke
				(width 0.1)
				(type default)
			)
			(layer "B.Fab")
		)
		(fp_line
			(start 0.12065 0.2794)
			(end 0.12065 0.3048)
			(stroke
				(width 0.1)
				(type default)
			)
			(layer "B.Fab")
		)
		(fp_line
			(start -0.120396 0.2794)
			(end 0.12065 0.2794)
			(stroke
				(width 0.1)
				(type default)
			)
			(layer "B.Fab")
		)
		(fp_line
			(start 0.67945 0.3048)
			(end 0.67945 -0.305054)
			(stroke
				(width 0.1)
				(type default)
			)
			(layer "B.Fab")
		)
		(fp_line
			(start 0.12065 0.3048)
			(end 0.67945 0.3048)
			(stroke
				(width 0.1)
				(type default)
			)
			(layer "B.Fab")
		)
		(fp_line
			(start -0.120396 0.3048)
			(end -0.120396 0.2794)
			(stroke
				(width 0.1)
				(type default)
			)
			(layer "B.Fab")
		)
		(fp_line
			(start -0.67945 0.3048)
			(end -0.120396 0.3048)
			(stroke
				(width 0.1)
				(type default)
			)
			(layer "B.Fab")
		)
		(pad "1" smd circle
			(at 0.40005 0 270)
			(size 0 0)
			(layers "B.Cu" "B.Mask" "B.Paste")
			(net "P3V3_AUX")
		)
		(pad "2" smd circle
			(at -0.40005 0 270)
			(size 0 0)
			(layers "B.Cu" "B.Mask" "B.Paste")
			(net "SMB_MB_PDB_R_SDA")
		)
	)
)
